(kicad_pcb
	(version 20260206)
	(generator "pcbnew")
	(generator_version "10.0")
	(general
		(thickness 1.6)
		(legacy_teardrops no)
	)
	(paper "A4")
	(title_block
		(title "v1-pdb — T6M_PDB_D_0927_0900.brd")
		(comment 1 "Open CloudServer (Microsoft) / footprint 320 of 321 (J18), pads 1-46 of 46")
	)
	(layers
		(0 "F.Cu" signal "TOP")
		(4 "In1.Cu" signal "GND")
		(6 "In2.Cu" signal "IN1")
		(8 "In3.Cu" signal "VCC")
		(10 "In4.Cu" signal "VCC1")
		(12 "In5.Cu" signal "IN2")
		(14 "In6.Cu" signal "GND1")
		(2 "B.Cu" signal "BOTTOM")
		(9 "F.Adhes" user "F.Adhesive")
		(11 "B.Adhes" user "B.Adhesive")
		(13 "F.Paste" user "Package Geometry/Pastemask Top")
		(15 "B.Paste" user "Package Geometry/Pastemask Bottom")
		(5 "F.SilkS" user "Ref Des/Silkscreen Top")
		(7 "B.SilkS" user "Ref Des/Silkscreen Bottom")
		(1 "F.Mask" user "Board Geometry/Soldermask Top")
		(3 "B.Mask" user "Board Geometry/Soldermask Bottom")
		(17 "Dwgs.User" user "User.Drawings")
		(19 "Cmts.User" user "User.Comments")
		(21 "Eco1.User" user "User.Eco1")
		(23 "Eco2.User" user "User.Eco2")
		(25 "Edge.Cuts" user "Board Geometry/Outline")
		(27 "Margin" user)
		(31 "F.CrtYd" user "Package Geometry/Place Bound Top")
		(29 "B.CrtYd" user "Package Geometry/Place Bound Bottom")
		(35 "F.Fab" user "Ref Des/Assembly Top")
		(33 "B.Fab" user "Ref Des/Assembly Bottom")
	)
	(footprint ""
		(layer "B.Cu")
		(at 44.03979 -497.21008 90)
		(property "Reference" "J18"
			(at 6.695948 -2.740406 0)
			(unlocked yes)
			(layer "B.SilkS")
			(effects
				(font
					(size 0.7874 0.5842)
					(thickness 0.1524)
				)
				(justify left mirror)
			)
		)
		(property "Value" ""
			(at 0 0 90)
			(layer "B.Fab")
			(effects
				(font
					(size 1.27 1.27)
				)
				(justify mirror)
			)
		)
		(duplicate_pad_numbers_are_jumpers no)
		(pad "" np_thru_hole circle
			(at -1.35001 -2.54)
			(size 2.5146 2.5146)
			(drill 2.5146)
			(layers "*.Cu" "*.Mask")
			(clearance 0.381)
			(thermal_gap 0.381)
		)
		(pad "" np_thru_hole circle
			(at 0 50.8)
			(size 2.5146 2.5146)
			(drill 2.5146)
			(layers "*.Cu" "*.Mask")
			(clearance 0.381)
			(thermal_gap 0.381)
		)
		(pad "P1" thru_hole rect
			(at 0 0)
			(size 1.1684 1.1684)
			(drill 0.762)
			(layers "*.Cu" "*.Mask")
			(remove_unused_layers no)
			(net "GND")
			(clearance 0.0508)
			(padstack
				(mode front_inner_back)
				(layer "Inner"
					(shape circle)
					(size 1.1684 1.1684)
					(clearance 0.0508)
				)
				(layer "B.Cu"
					(shape rect)
					(size 1.1684 1.1684)
					(thermal_gap 0.0508)
					(clearance 0.0508)
				)
			)
		)
		(pad "P2" thru_hole circle
			(at 0 2.54)
			(size 1.1684 1.1684)
			(drill 0.762)
			(layers "*.Cu" "*.Mask")
			(remove_unused_layers no)
			(net "GND")
			(clearance 0.0508)
			(thermal_gap 0.0508)
		)
		(pad "P3" thru_hole circle
			(at 0 5.08)
			(size 1.1684 1.1684)
			(drill 0.762)
			(layers "*.Cu" "*.Mask")
			(remove_unused_layers no)
			(net "GND")
			(clearance 0.0508)
			(thermal_gap 0.0508)
		)
		(pad "P4" thru_hole circle
			(at 0 7.62)
			(size 1.1684 1.1684)
			(drill 0.762)
			(layers "*.Cu" "*.Mask")
			(remove_unused_layers no)
			(net "GND")
			(clearance 0.0508)
			(thermal_gap 0.0508)
		)
		(pad "P5" thru_hole circle
			(at 0 10.16)
			(size 1.1684 1.1684)
			(drill 0.762)
			(layers "*.Cu" "*.Mask")
			(remove_unused_layers no)
			(net "GND")
			(clearance 0.0508)
			(thermal_gap 0.0508)
		)
		(pad "P6" thru_hole circle
			(at 0 12.7)
			(size 1.1684 1.1684)
			(drill 0.762)
			(layers "*.Cu" "*.Mask")
			(remove_unused_layers no)
			(net "GND")
			(clearance 0.0508)
			(thermal_gap 0.0508)
		)
		(pad "P7" thru_hole circle
			(at 0 15.24)
			(size 1.1684 1.1684)
			(drill 0.762)
			(layers "*.Cu" "*.Mask")
			(remove_unused_layers no)
			(net "GND")
			(clearance 0.0508)
			(thermal_gap 0.0508)
		)
		(pad "P8" thru_hole circle
			(at 0 17.78)
			(size 1.1684 1.1684)
			(drill 0.762)
			(layers "*.Cu" "*.Mask")
			(remove_unused_layers no)
			(net "GND")
			(clearance 0.0508)
			(thermal_gap 0.0508)
		)
		(pad "P9" thru_hole circle
			(at 0 20.32)
			(size 1.1684 1.1684)
			(drill 0.762)
			(layers "*.Cu" "*.Mask")
			(remove_unused_layers no)
			(net "P12V")
			(clearance 0.0508)
			(thermal_gap 0.0508)
		)
		(pad "P10" thru_hole circle
			(at 0 22.86)
			(size 1.1684 1.1684)
			(drill 0.762)
			(layers "*.Cu" "*.Mask")
			(remove_unused_layers no)
			(net "P12V")
			(clearance 0.0508)
			(thermal_gap 0.0508)
		)
		(pad "P11" thru_hole circle
			(at 0 25.4)
			(size 1.1684 1.1684)
			(drill 0.762)
			(layers "*.Cu" "*.Mask")
			(remove_unused_layers no)
			(net "P12V")
			(clearance 0.0508)
			(thermal_gap 0.0508)
		)
		(pad "P12" thru_hole circle
			(at 0 27.94)
			(size 1.1684 1.1684)
			(drill 0.762)
			(layers "*.Cu" "*.Mask")
			(remove_unused_layers no)
			(net "P12V")
			(clearance 0.0508)
			(thermal_gap 0.0508)
		)
		(pad "P13" thru_hole circle
			(at 0 30.48)
			(size 1.1684 1.1684)
			(drill 0.762)
			(layers "*.Cu" "*.Mask")
			(remove_unused_layers no)
			(net "P12V")
			(clearance 0.0508)
			(thermal_gap 0.0508)
		)
		(pad "P14" thru_hole circle
			(at 0 33.02)
			(size 1.1684 1.1684)
			(drill 0.762)
			(layers "*.Cu" "*.Mask")
			(remove_unused_layers no)
			(net "P12V")
			(clearance 0.0508)
			(thermal_gap 0.0508)
		)
		(pad "P15" thru_hole circle
			(at 0 35.56)
			(size 1.1684 1.1684)
			(drill 0.762)
			(layers "*.Cu" "*.Mask")
			(remove_unused_layers no)
			(net "P12V")
			(clearance 0.0508)
			(thermal_gap 0.0508)
		)
		(pad "P16" thru_hole circle
			(at 0 38.1)
			(size 1.1684 1.1684)
			(drill 0.762)
			(layers "*.Cu" "*.Mask")
			(remove_unused_layers no)
			(net "P12V")
			(clearance 0.0508)
			(thermal_gap 0.0508)
		)
		(pad "P17" thru_hole circle
			(at -2.70002 38.1)
			(size 1.1684 1.1684)
			(drill 0.762)
			(layers "*.Cu" "*.Mask")
			(remove_unused_layers no)
			(net "P12V")
			(clearance 0.0508)
			(thermal_gap 0.0508)
		)
		(pad "P18" thru_hole circle
			(at -2.70002 35.56)
			(size 1.1684 1.1684)
			(drill 0.762)
			(layers "*.Cu" "*.Mask")
			(remove_unused_layers no)
			(net "P12V")
			(clearance 0.0508)
			(thermal_gap 0.0508)
		)
		(pad "P19" thru_hole circle
			(at -2.70002 33.02)
			(size 1.1684 1.1684)
			(drill 0.762)
			(layers "*.Cu" "*.Mask")
			(remove_unused_layers no)
			(net "P12V")
			(clearance 0.0508)
			(thermal_gap 0.0508)
		)
		(pad "P20" thru_hole circle
			(at -2.70002 30.48)
			(size 1.1684 1.1684)
			(drill 0.762)
			(layers "*.Cu" "*.Mask")
			(remove_unused_layers no)
			(net "P12V")
			(clearance 0.0508)
			(thermal_gap 0.0508)
		)
		(pad "P21" thru_hole circle
			(at -2.70002 27.94)
			(size 1.1684 1.1684)
			(drill 0.762)
			(layers "*.Cu" "*.Mask")
			(remove_unused_layers no)
			(net "P12V")
			(clearance 0.0508)
			(thermal_gap 0.0508)
		)
		(pad "P22" thru_hole circle
			(at -2.70002 25.4)
			(size 1.1684 1.1684)
			(drill 0.762)
			(layers "*.Cu" "*.Mask")
			(remove_unused_layers no)
			(net "P12V")
			(clearance 0.0508)
			(thermal_gap 0.0508)
		)
		(pad "P23" thru_hole circle
			(at -2.70002 22.86)
			(size 1.1684 1.1684)
			(drill 0.762)
			(layers "*.Cu" "*.Mask")
			(remove_unused_layers no)
			(net "P12V")
			(clearance 0.0508)
			(thermal_gap 0.0508)
		)
		(pad "P24" thru_hole circle
			(at -2.70002 20.32)
			(size 1.1684 1.1684)
			(drill 0.762)
			(layers "*.Cu" "*.Mask")
			(remove_unused_layers no)
			(net "P12V")
			(clearance 0.0508)
			(thermal_gap 0.0508)
		)
		(pad "P25" thru_hole circle
			(at -2.70002 17.78)
			(size 1.1684 1.1684)
			(drill 0.762)
			(layers "*.Cu" "*.Mask")
			(remove_unused_layers no)
			(net "GND")
			(clearance 0.0508)
			(thermal_gap 0.0508)
		)
		(pad "P26" thru_hole circle
			(at -2.70002 15.24)
			(size 1.1684 1.1684)
			(drill 0.762)
			(layers "*.Cu" "*.Mask")
			(remove_unused_layers no)
			(net "GND")
			(clearance 0.0508)
			(thermal_gap 0.0508)
		)
		(pad "P27" thru_hole circle
			(at -2.70002 12.7)
			(size 1.1684 1.1684)
			(drill 0.762)
			(layers "*.Cu" "*.Mask")
			(remove_unused_layers no)
			(net "GND")
			(clearance 0.0508)
			(thermal_gap 0.0508)
		)
		(pad "P28" thru_hole circle
			(at -2.70002 10.16)
			(size 1.1684 1.1684)
			(drill 0.762)
			(layers "*.Cu" "*.Mask")
			(remove_unused_layers no)
			(net "GND")
			(clearance 0.0508)
			(thermal_gap 0.0508)
		)
		(pad "P29" thru_hole circle
			(at -2.70002 7.62)
			(size 1.1684 1.1684)
			(drill 0.762)
			(layers "*.Cu" "*.Mask")
			(remove_unused_layers no)
			(net "GND")
			(clearance 0.0508)
			(thermal_gap 0.0508)
		)
		(pad "P30" thru_hole circle
			(at -2.70002 5.08)
			(size 1.1684 1.1684)
			(drill 0.762)
			(layers "*.Cu" "*.Mask")
			(remove_unused_layers no)
			(net "GND")
			(clearance 0.0508)
			(thermal_gap 0.0508)
		)
		(pad "P31" thru_hole circle
			(at -2.70002 2.54)
			(size 1.1684 1.1684)
			(drill 0.762)
			(layers "*.Cu" "*.Mask")
			(remove_unused_layers no)
			(net "GND")
			(clearance 0.0508)
			(thermal_gap 0.0508)
		)
		(pad "P32" thru_hole circle
			(at -2.70002 0)
			(size 1.1684 1.1684)
			(drill 0.762)
			(layers "*.Cu" "*.Mask")
			(remove_unused_layers no)
			(net "GND")
			(clearance 0.0508)
			(thermal_gap 0.0508)
		)
		(pad "S1" thru_hole circle
			(at 0.55499 41.60012)
			(size 1.1684 1.1684)
			(drill 0.762)
			(layers "*.Cu" "*.Mask")
			(remove_unused_layers no)
			(net "T12_BLAD1_TXD")
			(clearance 0.0508)
			(thermal_gap 0.0508)
		)
		(pad "S2" thru_hole circle
			(at -0.71501 42.87012)
			(size 1.1684 1.1684)
			(drill 0.762)
			(layers "*.Cu" "*.Mask")
			(remove_unused_layers no)
			(net "T12_BLAD1_RXD")
			(clearance 0.0508)
			(thermal_gap 0.0508)
		)
		(pad "S3" thru_hole circle
			(at 0.55499 44.14012)
			(size 1.1684 1.1684)
			(drill 0.762)
			(layers "*.Cu" "*.Mask")
			(remove_unused_layers no)
			(net "T12_BLAD1_EN")
			(clearance 0.0508)
			(thermal_gap 0.0508)
		)
		(pad "S4" thru_hole circle
			(at -0.71501 45.41012)
			(size 1.1684 1.1684)
			(drill 0.762)
			(layers "*.Cu" "*.Mask")
			(remove_unused_layers no)
			(net "T12_BLAD2_EN")
			(clearance 0.0508)
			(thermal_gap 0.0508)
		)
		(pad "S5" thru_hole circle
			(at 0.55499 46.68012)
			(size 1.1684 1.1684)
			(drill 0.762)
			(layers "*.Cu" "*.Mask")
			(remove_unused_layers no)
			(net "T12_BLAD2_TXD")
			(clearance 0.0508)
			(thermal_gap 0.0508)
		)
		(pad "S6" thru_hole circle
			(at -0.71501 47.95012)
			(size 1.1684 1.1684)
			(drill 0.762)
			(layers "*.Cu" "*.Mask")
			(remove_unused_layers no)
			(net "T12_BLAD2_RXD")
			(clearance 0.0508)
			(thermal_gap 0.0508)
		)
		(pad "S7" thru_hole circle
			(at -3.25501 47.95012)
			(size 1.1684 1.1684)
			(drill 0.762)
			(layers "*.Cu" "*.Mask")
			(remove_unused_layers no)
			(net "T12_BLAD4_RXD")
			(clearance 0.0508)
			(thermal_gap 0.0508)
		)
		(pad "S8" thru_hole circle
			(at -1.98501 46.68012)
			(size 1.1684 1.1684)
			(drill 0.762)
			(layers "*.Cu" "*.Mask")
			(remove_unused_layers no)
			(net "T12_BLAD4_TXD")
			(clearance 0.0508)
			(thermal_gap 0.0508)
		)
		(pad "S9" thru_hole circle
			(at -3.25501 45.41012)
			(size 1.1684 1.1684)
			(drill 0.762)
			(layers "*.Cu" "*.Mask")
			(remove_unused_layers no)
			(net "T12_BLAD4_EN")
			(clearance 0.0508)
			(thermal_gap 0.0508)
		)
		(pad "S10" thru_hole circle
			(at -1.98501 44.14012)
			(size 1.1684 1.1684)
			(drill 0.762)
			(layers "*.Cu" "*.Mask")
			(remove_unused_layers no)
			(net "T12_BLAD3_EN")
			(clearance 0.0508)
			(thermal_gap 0.0508)
		)
		(pad "S11" thru_hole circle
			(at -3.25501 42.87012)
			(size 1.1684 1.1684)
			(drill 0.762)
			(layers "*.Cu" "*.Mask")
			(remove_unused_layers no)
			(net "T12_BLAD3_RXD")
			(clearance 0.0508)
			(thermal_gap 0.0508)
		)
		(pad "S12" thru_hole circle
			(at -1.98501 41.60012)
			(size 1.1684 1.1684)
			(drill 0.762)
			(layers "*.Cu" "*.Mask")
			(remove_unused_layers no)
			(net "T12_BLAD3_TXD")
			(clearance 0.0508)
			(thermal_gap 0.0508)
		)
	)
)
